(kicad_pcb
	(version 20241229)
	(generator "pcbnew")
	(generator_version "9.0")
	(general
		(thickness 1.59)
		(legacy_teardrops no)
	)
	(paper "A3")
	(title_block
		(title "usb-c-power-adapter")
		(date "2025-06-24")
		(rev "1.1.2")
		(company "Antmicro")
		(comment 9 "footprints 84-88 of 122")
	)
	(layers
		(0 "F.Cu" signal)
		(4 "In1.Cu" signal)
		(6 "In2.Cu" signal)
		(2 "B.Cu" signal)
		(9 "F.Adhes" user "F.Adhesive")
		(11 "B.Adhes" user "B.Adhesive")
		(13 "F.Paste" user)
		(15 "B.Paste" user)
		(5 "F.SilkS" user "F.Silkscreen")
		(7 "B.SilkS" user "B.Silkscreen")
		(1 "F.Mask" user)
		(3 "B.Mask" user)
		(17 "Dwgs.User" user "User.Drawings")
		(19 "Cmts.User" user "User.Comments")
		(21 "Eco1.User" user "User.Eco1")
		(23 "Eco2.User" user "User.Eco2")
		(25 "Edge.Cuts" user)
		(27 "Margin" user)
		(31 "F.CrtYd" user "F.Courtyard")
		(29 "B.CrtYd" user "B.Courtyard")
		(35 "F.Fab" user)
		(33 "B.Fab" user)
	)
	(footprint "antmicro-footprints:C_1206_3216Metric"
		(layer "B.Cu")
		(at 91.2 97.85 90)
		(descr "Capacitor SMD 1206")
		(tags "capacitor SMD 1206")
		(property "Reference" "C34"
			(at 23.428 -4.838 180)
			(layer "B.SilkS")
			(effects
				(font
					(size 0.7 0.7)
					(thickness 0.15)
				)
				(justify left bottom mirror)
			)
		)
		(property "Value" "C_47u_25V_1206"
			(at 0 -2.101 90)
			(layer "B.Fab")
			(effects
				(font
					(size 0.7 0.7)
					(thickness 0.15)
				)
				(justify right bottom mirror)
			)
		)
		(property "Datasheet" "https://product.tdk.com/en/search/capacitor/ceramic/mlcc/info?part_no=C3216X5R1E476M160AC"
			(at 0 0 90)
			(layer "F.Fab")
			(hide yes)
			(effects
				(font
					(size 1.27 1.27)
					(thickness 0.15)
				)
			)
		)
		(property "Description" "SMD Multilayer Ceramic Capacitor, 47 µF, 25 V, 1206 [3216 Metric], ± 20%, X5R"
			(at 0 0 90)
			(layer "F.Fab")
			(hide yes)
			(effects
				(font
					(size 1.27 1.27)
					(thickness 0.15)
				)
			)
		)
		(property "MPN" "C3216X5R1E476M160AC"
			(at 0 0 90)
			(unlocked yes)
			(layer "B.Fab")
			(hide yes)
			(effects
				(font
					(size 1 1)
					(thickness 0.15)
				)
				(justify mirror)
			)
		)
		(property "Val" "47u"
			(at 0 0 90)
			(unlocked yes)
			(layer "B.Fab")
			(hide yes)
			(effects
				(font
					(size 1 1)
					(thickness 0.15)
				)
				(justify mirror)
			)
		)
		(property "Voltage" "25V"
			(at 0 0 90)
			(unlocked yes)
			(layer "B.Fab")
			(hide yes)
			(effects
				(font
					(size 1 1)
					(thickness 0.15)
				)
				(justify mirror)
			)
		)
		(property "Author" "Antmicro"
			(at 0 0 90)
			(unlocked yes)
			(layer "B.Fab")
			(hide yes)
			(effects
				(font
					(size 1 1)
					(thickness 0.15)
				)
				(justify mirror)
			)
		)
		(property "License" "Apache-2.0"
			(at 0 0 90)
			(unlocked yes)
			(layer "B.Fab")
			(hide yes)
			(effects
				(font
					(size 1 1)
					(thickness 0.15)
				)
				(justify mirror)
			)
		)
		(property "Manufacturer" "TDK"
			(at 0 0 90)
			(unlocked yes)
			(layer "B.Fab")
			(hide yes)
			(effects
				(font
					(size 1 1)
					(thickness 0.15)
				)
				(justify mirror)
			)
		)
		(property "Dielectric" "X5R"
			(at 0 0 90)
			(unlocked yes)
			(layer "B.Fab")
			(hide yes)
			(effects
				(font
					(size 1 1)
					(thickness 0.15)
				)
				(justify mirror)
			)
		)
		(property "Public" "False"
			(at 0 0 90)
			(unlocked yes)
			(layer "B.Fab")
			(hide yes)
			(effects
				(font
					(size 1 1)
					(thickness 0.15)
				)
				(justify mirror)
			)
		)
		(sheetname "/DC-DC Converters/")
		(sheetfile "dc-dc_converters.kicad_sch")
		(attr smd)
		(fp_line
			(start -0.8 -0.901)
			(end 0.8 -0.901)
			(stroke
				(width 0.15)
				(type solid)
			)
			(layer "B.SilkS")
		)
		(fp_line
			(start -0.8 0.899)
			(end 0.8 0.899)
			(stroke
				(width 0.15)
				(type solid)
			)
			(layer "B.SilkS")
		)
		(fp_rect
			(start -2.325 1.15)
			(end 2.325 -1.15)
			(stroke
				(width 0.05)
				(type default)
			)
			(fill no)
			(layer "B.CrtYd")
		)
		(fp_rect
			(start -1.6 0.799)
			(end 1.6 -0.801)
			(stroke
				(width 0.15)
				(type solid)
			)
			(fill no)
			(layer "B.Fab")
		)
		(pad "1" smd roundrect
			(at -1.5 -0.001 90)
			(size 1.15 1.8)
			(layers "B.Cu" "B.Mask" "B.Paste")
			(roundrect_rratio 0.25)
			(net 2 "GND")
			(pintype "passive")
		)
		(pad "2" smd roundrect
			(at 1.5 -0.001 90)
			(size 1.15 1.8)
			(layers "B.Cu" "B.Mask" "B.Paste")
			(roundrect_rratio 0.25)
			(net 5 "+12V")
			(pintype "passive")
		)
	)
	(footprint "antmicro-footprints:WSON-6-1EP_2x2mm_P0.65mm"
		(layer "B.Cu")
		(at 91.6 66.8 180)
		(property "Reference" "U5"
			(at 1.324 0.75 90)
			(layer "B.SilkS")
			(effects
				(font
					(size 0.7 0.7)
					(thickness 0.15)
				)
				(justify left bottom mirror)
			)
		)
		(property "Value" "TVS2200DRVR"
			(at 0 -2.2 0)
			(layer "B.Fab")
			(effects
				(font
					(size 0.7 0.7)
					(thickness 0.15)
				)
				(justify left bottom mirror)
			)
		)
		(property "Datasheet" "https://www.ti.com/lit/ds/symlink/tvs2200.pdf?ts=1712230685180&ref_url=https%253A%252F%252Fwww.ti.com%252Fproduct%252FTVS2200"
			(at 0 0 180)
			(layer "F.Fab")
			(hide yes)
			(effects
				(font
					(size 1.27 1.27)
					(thickness 0.15)
				)
			)
		)
		(property "Description" "ESD Protection Device, 1 kV, WSON-6, 22 V, 105 pF"
			(at 0 0 180)
			(layer "F.Fab")
			(hide yes)
			(effects
				(font
					(size 1.27 1.27)
					(thickness 0.15)
				)
			)
		)
		(property "MPN" "TVS2200DRVR"
			(at 0 0 180)
			(unlocked yes)
			(layer "B.Fab")
			(hide yes)
			(effects
				(font
					(size 1 1)
					(thickness 0.15)
				)
				(justify mirror)
			)
		)
		(property "Manufacturer" "Texas Instruments"
			(at 0 0 180)
			(unlocked yes)
			(layer "B.Fab")
			(hide yes)
			(effects
				(font
					(size 1 1)
					(thickness 0.15)
				)
				(justify mirror)
			)
		)
		(property "License" "Apache-2.0"
			(at 0 0 180)
			(unlocked yes)
			(layer "B.Fab")
			(hide yes)
			(effects
				(font
					(size 1 1)
					(thickness 0.15)
				)
				(justify mirror)
			)
		)
		(property "Author" "Antmicro"
			(at 0 0 180)
			(unlocked yes)
			(layer "B.Fab")
			(hide yes)
			(effects
				(font
					(size 1 1)
					(thickness 0.15)
				)
				(justify mirror)
			)
		)
		(sheetname "/USB PD/")
		(sheetfile "usb_pd.kicad_sch")
		(attr smd)
		(fp_line
			(start 1 -1)
			(end -1 -1)
			(stroke
				(width 0.12)
				(type solid)
			)
			(layer "B.SilkS")
		)
		(fp_line
			(start -1.05 1)
			(end 1 1)
			(stroke
				(width 0.12)
				(type solid)
			)
			(layer "B.SilkS")
		)
		(fp_circle
			(center -1.275 1.075)
			(end -1.224 1.075)
			(stroke
				(width 0.15)
				(type solid)
			)
			(fill yes)
			(layer "B.SilkS")
		)
		(fp_rect
			(start -1.45 1.25)
			(end 1.45 -1.25)
			(stroke
				(width 0.05)
				(type solid)
			)
			(fill no)
			(layer "B.CrtYd")
		)
		(pad "1" smd roundrect
			(at -0.975 0.652 180)
			(size 0.45 0.4)
			(layers "B.Cu" "B.Mask" "B.Paste")
			(roundrect_rratio 0.25)
			(net 2 "GND")
			(pinfunction "GND")
			(pintype "passive")
		)
		(pad "2" smd roundrect
			(at -0.975 0 180)
			(size 0.45 0.4)
			(layers "B.Cu" "B.Mask" "B.Paste")
			(roundrect_rratio 0.25)
			(net 2 "GND")
			(pinfunction "GND")
			(pintype "passive")
		)
		(pad "3" smd roundrect
			(at -0.975 -0.65 180)
			(size 0.45 0.4)
			(layers "B.Cu" "B.Mask" "B.Paste")
			(roundrect_rratio 0.25)
			(net 2 "GND")
			(pinfunction "GND")
			(pintype "passive")
		)
		(pad "4" smd roundrect
			(at 0.973 -0.65 180)
			(size 0.45 0.4)
			(layers "B.Cu" "B.Mask" "B.Paste")
			(roundrect_rratio 0.25)
			(net 6 "VBUS")
			(pinfunction "IN")
			(pintype "passive")
		)
		(pad "5" smd roundrect
			(at 0.973 0 180)
			(size 0.45 0.4)
			(layers "B.Cu" "B.Mask" "B.Paste")
			(roundrect_rratio 0.25)
			(net 6 "VBUS")
			(pinfunction "IN")
			(pintype "passive")
		)
		(pad "6" smd roundrect
			(at 0.973 0.652 180)
			(size 0.45 0.4)
			(layers "B.Cu" "B.Mask" "B.Paste")
			(roundrect_rratio 0.25)
			(net 6 "VBUS")
			(pinfunction "IN")
			(pintype "passive")
		)
		(pad "7" smd roundrect
			(at 0 0 180)
			(size 1.12 1.72)
			(layers "B.Cu" "B.Mask" "B.Paste")
			(roundrect_rratio 0.1)
			(net 2 "GND")
			(pinfunction "GND")
			(pintype "passive")
		)
	)
	(footprint "antmicro-footprints:C_0603_1608Metric"
		(layer "B.Cu")
		(at 85.726 90.75 180)
		(descr "Capacitor SMD 0603")
		(tags "capacitor 0603")
		(property "Reference" "C21"
			(at -1.474 -1.65 180)
			(layer "B.SilkS")
			(effects
				(font
					(size 0.7 0.7)
					(thickness 0.15)
				)
				(justify left bottom mirror)
			)
		)
		(property "Value" "C_10u_25V_0603"
			(at -1.42757 -1.770288 0)
			(layer "B.Fab")
			(effects
				(font
					(size 0.7 0.7)
					(thickness 0.15)
				)
				(justify left bottom mirror)
			)
		)
		(property "Datasheet" "https://product.tdk.com/en/search/capacitor/ceramic/mlcc/info?part_no=C1608X5R1E106M080AC"
			(at 0 0 180)
			(layer "F.Fab")
			(hide yes)
			(effects
				(font
					(size 1.27 1.27)
					(thickness 0.15)
				)
			)
		)
		(property "Description" "SMD Multilayer Ceramic Capacitor, 10 µF, 25 V, 0603 [1608 Metric], ± 20%, X5R, C"
			(at 0 0 180)
			(layer "F.Fab")
			(hide yes)
			(effects
				(font
					(size 1.27 1.27)
					(thickness 0.15)
				)
			)
		)
		(property "MPN" "C1608X5R1E106M080AC"
			(at 0 0 180)
			(unlocked yes)
			(layer "B.Fab")
			(hide yes)
			(effects
				(font
					(size 1 1)
					(thickness 0.15)
				)
				(justify mirror)
			)
		)
		(property "Manufacturer" "TDK"
			(at 0 0 180)
			(unlocked yes)
			(layer "B.Fab")
			(hide yes)
			(effects
				(font
					(size 1 1)
					(thickness 0.15)
				)
				(justify mirror)
			)
		)
		(property "License" "Apache-2.0"
			(at 0 0 180)
			(unlocked yes)
			(layer "B.Fab")
			(hide yes)
			(effects
				(font
					(size 1 1)
					(thickness 0.15)
				)
				(justify mirror)
			)
		)
		(property "Author" "Antmicro"
			(at 0 0 180)
			(unlocked yes)
			(layer "B.Fab")
			(hide yes)
			(effects
				(font
					(size 1 1)
					(thickness 0.15)
				)
				(justify mirror)
			)
		)
		(property "Val" "10u"
			(at 0 0 180)
			(unlocked yes)
			(layer "B.Fab")
			(hide yes)
			(effects
				(font
					(size 1 1)
					(thickness 0.15)
				)
				(justify mirror)
			)
		)
		(property "Voltage" "25V"
			(at 0 0 180)
			(unlocked yes)
			(layer "B.Fab")
			(hide yes)
			(effects
				(font
					(size 1 1)
					(thickness 0.15)
				)
				(justify mirror)
			)
		)
		(property "Dielectric" ""
			(at 0 0 180)
			(unlocked yes)
			(layer "B.Fab")
			(hide yes)
			(effects
				(font
					(size 1 1)
					(thickness 0.15)
				)
				(justify mirror)
			)
		)
		(sheetname "/DC-DC Converters/")
		(sheetfile "dc-dc_converters.kicad_sch")
		(attr smd)
		(fp_line
			(start 0.15 0.4)
			(end -0.15 0.4)
			(stroke
				(width 0.15)
				(type solid)
			)
			(layer "B.SilkS")
		)
		(fp_line
			(start 0.15 -0.4)
			(end -0.15 -0.4)
			(stroke
				(width 0.15)
				(type solid)
			)
			(layer "B.SilkS")
		)
		(fp_rect
			(start -1.25 0.65)
			(end 1.25 -0.65)
			(stroke
				(width 0.05)
				(type solid)
			)
			(fill no)
			(layer "B.CrtYd")
		)
		(fp_rect
			(start -0.8 0.4)
			(end 0.8 -0.4)
			(stroke
				(width 0.15)
				(type solid)
			)
			(fill no)
			(layer "B.Fab")
		)
		(pad "1" smd roundrect
			(at -0.7 0 180)
			(size 0.8 1)
			(layers "B.Cu" "B.Mask" "B.Paste")
			(roundrect_rratio 0.2)
			(net 2 "GND")
			(pintype "passive")
		)
		(pad "2" smd roundrect
			(at 0.7 0 180)
			(size 0.8 1)
			(layers "B.Cu" "B.Mask" "B.Paste")
			(roundrect_rratio 0.2)
			(net 5 "+12V")
			(pintype "passive")
		)
	)
	(footprint "antmicro-footprints:C_0402_1005Metric"
		(layer "B.Cu")
		(at 96.4 89.05 -90)
		(descr "Capacitor SMD 0402")
		(tags "capacitor SMD 0402")
		(property "Reference" "C42"
			(at -1.1 0.6 90)
			(layer "B.SilkS")
			(effects
				(font
					(size 0.7 0.7)
					(thickness 0.15)
				)
				(justify left bottom mirror)
			)
		)
		(property "Value" "C_1u_25V_0402"
			(at -1.022927 -2.155213 90)
			(layer "B.Fab")
			(effects
				(font
					(size 0.7 0.7)
					(thickness 0.15)
				)
				(justify left bottom mirror)
			)
		)
		(property "Datasheet" "https://www.murata.com/products/productdetail?partno=GRM155R61E105KE11%23"
			(at 0 0 270)
			(layer "F.Fab")
			(hide yes)
			(effects
				(font
					(size 1.27 1.27)
					(thickness 0.15)
				)
			)
		)
		(property "Description" "SMD Multilayer Ceramic Capacitor, 1 µF, 25 V, 0402 [1005 Metric], ± 10%, X5R, GRM Series"
			(at 0 0 270)
			(layer "F.Fab")
			(hide yes)
			(effects
				(font
					(size 1.27 1.27)
					(thickness 0.15)
				)
			)
		)
		(property "MPN" "GRM155R61E105KE11J"
			(at 0 0 270)
			(unlocked yes)
			(layer "B.Fab")
			(hide yes)
			(effects
				(font
					(size 1 1)
					(thickness 0.15)
				)
				(justify mirror)
			)
		)
		(property "Manufacturer" "Murata"
			(at 0 0 270)
			(unlocked yes)
			(layer "B.Fab")
			(hide yes)
			(effects
				(font
					(size 1 1)
					(thickness 0.15)
				)
				(justify mirror)
			)
		)
		(property "License" "Apache-2.0"
			(at 0 0 270)
			(unlocked yes)
			(layer "B.Fab")
			(hide yes)
			(effects
				(font
					(size 1 1)
					(thickness 0.15)
				)
				(justify mirror)
			)
		)
		(property "Author" "Antmicro"
			(at 0 0 270)
			(unlocked yes)
			(layer "B.Fab")
			(hide yes)
			(effects
				(font
					(size 1 1)
					(thickness 0.15)
				)
				(justify mirror)
			)
		)
		(property "Val" "1u"
			(at 0 0 270)
			(unlocked yes)
			(layer "B.Fab")
			(hide yes)
			(effects
				(font
					(size 1 1)
					(thickness 0.15)
				)
				(justify mirror)
			)
		)
		(property "Voltage" "25V"
			(at 0 0 270)
			(unlocked yes)
			(layer "B.Fab")
			(hide yes)
			(effects
				(font
					(size 1 1)
					(thickness 0.15)
				)
				(justify mirror)
			)
		)
		(property "Dielectric" "X5R"
			(at 0 0 270)
			(unlocked yes)
			(layer "B.Fab")
			(hide yes)
			(effects
				(font
					(size 1 1)
					(thickness 0.15)
				)
				(justify mirror)
			)
		)
		(sheetname "/DC-DC Converters/")
		(sheetfile "dc-dc_converters.kicad_sch")
		(attr smd)
		(fp_rect
			(start -0.925 0.47)
			(end 0.925 -0.47)
			(stroke
				(width 0.05)
				(type default)
			)
			(fill no)
			(layer "B.CrtYd")
		)
		(fp_line
			(start -0.494 0.25)
			(end -0.494 -0.248)
			(stroke
				(width 0.15)
				(type solid)
			)
			(layer "B.Fab")
		)
		(fp_line
			(start 0.504 0.25)
			(end -0.494 0.25)
			(stroke
				(width 0.15)
				(type solid)
			)
			(layer "B.Fab")
		)
		(fp_line
			(start -0.494 -0.248)
			(end 0.504 -0.248)
			(stroke
				(width 0.15)
				(type solid)
			)
			(layer "B.Fab")
		)
		(fp_line
			(start 0.504 -0.248)
			(end 0.504 0.25)
			(stroke
				(width 0.15)
				(type solid)
			)
			(layer "B.Fab")
		)
		(pad "1" smd roundrect
			(at -0.48 0 270)
			(size 0.59 0.64)
			(layers "B.Cu" "B.Mask" "B.Paste")
			(roundrect_rratio 0.25)
			(net 2 "GND")
			(pintype "passive")
		)
		(pad "2" smd roundrect
			(at 0.48 0 270)
			(size 0.59 0.64)
			(layers "B.Cu" "B.Mask" "B.Paste")
			(roundrect_rratio 0.25)
			(net 25 "+5V")
			(pintype "passive")
		)
	)
	(footprint "antmicro-footprints:C_0805_2012Metric"
		(layer "B.Cu")
		(at 99.75 98.2 90)
		(descr "Capacitor SMD 0805")
		(tags "capacitor SMD 0805")
		(property "Reference" "C36"
			(at 1.807 -0.69 180)
			(layer "B.SilkS")
			(effects
				(font
					(size 0.7 0.7)
					(thickness 0.15)
				)
				(justify right bottom mirror)
			)
		)
		(property "Value" "C_22u_25V_0805"
			(at -2.055717 -1.963152 90)
			(layer "B.Fab")
			(effects
				(font
					(size 0.7 0.7)
					(thickness 0.15)
				)
				(justify right bottom mirror)
			)
		)
		(property "Datasheet" "https://product.samsungsem.com/mlcc/CL21A226MAYNNN.do"
			(at 0 0 90)
			(layer "F.Fab")
			(hide yes)
			(effects
				(font
					(size 1.27 1.27)
					(thickness 0.15)
				)
			)
		)
		(property "Description" "SMT Multilayer Ceramic Capacitor, 22uF, +/-20%, 25V, X5R, 0805 [2012 Metric]"
			(at 0 0 90)
			(layer "F.Fab")
			(hide yes)
			(effects
				(font
					(size 1.27 1.27)
					(thickness 0.15)
				)
			)
		)
		(property "MPN" "CL21A226MAYNNNE"
			(at 0 0 90)
			(unlocked yes)
			(layer "B.Fab")
			(hide yes)
			(effects
				(font
					(size 1 1)
					(thickness 0.15)
				)
				(justify mirror)
			)
		)
		(property "Manufacturer" "Samsung Electro-Mechanics"
			(at 0 0 90)
			(unlocked yes)
			(layer "B.Fab")
			(hide yes)
			(effects
				(font
					(size 1 1)
					(thickness 0.15)
				)
				(justify mirror)
			)
		)
		(property "License" "Apache-2.0"
			(at 0 0 90)
			(unlocked yes)
			(layer "B.Fab")
			(hide yes)
			(effects
				(font
					(size 1 1)
					(thickness 0.15)
				)
				(justify mirror)
			)
		)
		(property "Author" "Antmicro"
			(at 0 0 90)
			(unlocked yes)
			(layer "B.Fab")
			(hide yes)
			(effects
				(font
					(size 1 1)
					(thickness 0.15)
				)
				(justify mirror)
			)
		)
		(property "Val" "22u"
			(at 0 0 90)
			(unlocked yes)
			(layer "B.Fab")
			(hide yes)
			(effects
				(font
					(size 1 1)
					(thickness 0.15)
				)
				(justify mirror)
			)
		)
		(property "Voltage" "25V"
			(at 0 0 90)
			(unlocked yes)
			(layer "B.Fab")
			(hide yes)
			(effects
				(font
					(size 1 1)
					(thickness 0.15)
				)
				(justify mirror)
			)
		)
		(property "Dielectric" "X5R"
			(at 0 0 90)
			(unlocked yes)
			(layer "B.Fab")
			(hide yes)
			(effects
				(font
					(size 1 1)
					(thickness 0.15)
				)
				(justify mirror)
			)
		)
		(property "Public" "False"
			(at 0 0 90)
			(unlocked yes)
			(layer "B.Fab")
			(hide yes)
			(effects
				(font
					(size 1 1)
					(thickness 0.15)
				)
				(justify mirror)
			)
		)
		(sheetname "/DC-DC Converters/")
		(sheetfile "dc-dc_converters.kicad_sch")
		(attr smd)
		(fp_line
			(start 0.3 -0.7)
			(end -0.3 -0.7)
			(stroke
				(width 0.15)
				(type solid)
			)
			(layer "B.SilkS")
		)
		(fp_line
			(start 0.3 0.7)
			(end -0.3 0.7)
			(stroke
				(width 0.15)
				(type solid)
			)
			(layer "B.SilkS")
		)
		(fp_rect
			(start 1.95 0.9)
			(end -1.95 -0.9)
			(stroke
				(width 0.05)
				(type default)
			)
			(fill no)
			(layer "B.CrtYd")
		)
		(fp_rect
			(start -0.95 0.675)
			(end 0.95 -0.675)
			(stroke
				(width 0.15)
				(type solid)
			)
			(fill no)
			(layer "B.Fab")
		)
		(pad "1" smd roundrect
			(at -1.1 0 90)
			(size 1.2 1.3)
			(layers "B.Cu" "B.Mask" "B.Paste")
			(roundrect_rratio 0.25)
			(net 2 "GND")
			(pintype "passive")
		)
		(pad "2" smd roundrect
			(at 1.1 0 90)
			(size 1.2 1.3)
			(layers "B.Cu" "B.Mask" "B.Paste")
			(roundrect_rratio 0.25)
			(net 5 "+12V")
			(pintype "passive")
		)
	)
)
